# T6G (Grand Teton) — schematic netlist excerpt (pin names and nets, part order shuffled) for the footprints in the layout excerpt that follows; sources: Cadence DE-HDL packaged netlist, KiCad conversion of 04192023_DAF0TMB3IC0_F0TG_MB_C_brd_V02_OCP.brd

C256  Q_CAP  4.7UF 6.3V 20% X6S  pkg 0402  page 323 : A = P0V9_CPU1_RT_2D ; B = GND
R240  Q_RES  100 1% CHIP  pkg 0402LF  page 217 : A = PVDDCR_CPU1_P1_RESET_N ; B = PVDDCR_CPU1_P1_RESET_N_R

(kicad_pcb
	(version 20260206)
	(generator "pcbnew")
	(generator_version "10.0")
	(general
		(thickness 1.6)
		(legacy_teardrops no)
	)
	(paper "A4")
	(title_block
		(title "04192023_DAF0TMB3IC0_F0TG_MB_C_brd_V02_OCP.brd")
		(comment 1 "Grand Teton / footprints 5577-5578 of 8354")
	)
	(layers
		(0 "F.Cu" signal "TOP")
		(4 "In1.Cu" signal "GND")
		(6 "In2.Cu" signal "IN1")
		(8 "In3.Cu" signal "GND1")
		(10 "In4.Cu" signal "IN2")
		(12 "In5.Cu" signal "GND2")
		(14 "In6.Cu" signal "IN3")
		(16 "In7.Cu" signal "GND3")
		(18 "In8.Cu" signal "VCC")
		(20 "In9.Cu" signal "VCC1")
		(22 "In10.Cu" signal "GND4")
		(24 "In11.Cu" signal "IN4")
		(26 "In12.Cu" signal "GND5")
		(28 "In13.Cu" signal "IN5")
		(30 "In14.Cu" signal "GND6")
		(32 "In15.Cu" signal "IN6")
		(34 "In16.Cu" signal "GND7")
		(2 "B.Cu" signal "BOTTOM")
		(9 "F.Adhes" user "F.Adhesive")
		(11 "B.Adhes" user "B.Adhesive")
		(13 "F.Paste" user "Package Geometry/Pastemask Top")
		(15 "B.Paste" user "Package Geometry/Pastemask Bottom")
		(5 "F.SilkS" user "Ref Des/Silkscreen Top")
		(7 "B.SilkS" user "Ref Des/Silkscreen Bottom")
		(1 "F.Mask" user "Board Geometry/Soldermask Top")
		(3 "B.Mask" user "Board Geometry/Soldermask Bottom")
		(17 "Dwgs.User" user "User.Drawings")
		(19 "Cmts.User" user "User.Comments")
		(21 "Eco1.User" user "User.Eco1")
		(23 "Eco2.User" user "User.Eco2")
		(25 "Edge.Cuts" user "Board Geometry/Outline")
		(27 "Margin" user)
		(31 "F.CrtYd" user "Package Geometry/Place Bound Top")
		(29 "B.CrtYd" user "Package Geometry/Place Bound Bottom")
		(35 "F.Fab" user "Ref Des/Assembly Top")
		(33 "B.Fab" user "Ref Des/Assembly Bottom")
	)
	(footprint ""
		(layer "B.Cu")
		(at 53.391308 -390.560052 90)
		(property "Reference" "C256"
			(at 0 0 90)
			(layer "B.SilkS")
			(hide yes)
			(effects
				(font
					(size 1.27 1.27)
				)
				(justify mirror)
			)
		)
		(property "Value" ""
			(at 0 0 90)
			(layer "B.Fab")
			(effects
				(font
					(size 1.27 1.27)
				)
				(justify mirror)
			)
		)
		(duplicate_pad_numbers_are_jumpers no)
		(fp_line
			(start 0.7874 -0.4064)
			(end -0.7874 -0.4064)
			(stroke
				(width 0.1524)
				(type default)
			)
			(layer "B.SilkS")
		)
		(fp_line
			(start -0.7874 -0.4064)
			(end -0.7874 0.4064)
			(stroke
				(width 0.1524)
				(type default)
			)
			(layer "B.SilkS")
		)
		(fp_line
			(start 0.7874 0.4064)
			(end 0.7874 -0.4064)
			(stroke
				(width 0.1524)
				(type default)
			)
			(layer "B.SilkS")
		)
		(fp_line
			(start -0.7874 0.4064)
			(end 0.7874 0.4064)
			(stroke
				(width 0.1524)
				(type default)
			)
			(layer "B.SilkS")
		)
		(fp_line
			(start 0.67945 -0.305054)
			(end 0.12065 -0.305054)
			(stroke
				(width 0.1)
				(type default)
			)
			(layer "B.Fab")
		)
		(fp_line
			(start 0.12065 -0.305054)
			(end 0.12065 -0.2794)
			(stroke
				(width 0.1)
				(type default)
			)
			(layer "B.Fab")
		)
		(fp_line
			(start -0.12065 -0.3048)
			(end -0.67945 -0.3048)
			(stroke
				(width 0.1)
				(type default)
			)
			(layer "B.Fab")
		)
		(fp_line
			(start -0.67945 -0.3048)
			(end -0.67945 0.3048)
			(stroke
				(width 0.1)
				(type default)
			)
			(layer "B.Fab")
		)
		(fp_line
			(start 0.12065 -0.2794)
			(end -0.12065 -0.2794)
			(stroke
				(width 0.1)
				(type default)
			)
			(layer "B.Fab")
		)
		(fp_line
			(start -0.12065 -0.2794)
			(end -0.12065 -0.3048)
			(stroke
				(width 0.1)
				(type default)
			)
			(layer "B.Fab")
		)
		(fp_line
			(start 0.12065 0.2794)
			(end 0.12065 0.3048)
			(stroke
				(width 0.1)
				(type default)
			)
			(layer "B.Fab")
		)
		(fp_line
			(start -0.120396 0.2794)
			(end 0.12065 0.2794)
			(stroke
				(width 0.1)
				(type default)
			)
			(layer "B.Fab")
		)
		(fp_line
			(start 0.67945 0.3048)
			(end 0.67945 -0.305054)
			(stroke
				(width 0.1)
				(type default)
			)
			(layer "B.Fab")
		)
		(fp_line
			(start 0.12065 0.3048)
			(end 0.67945 0.3048)
			(stroke
				(width 0.1)
				(type default)
			)
			(layer "B.Fab")
		)
		(fp_line
			(start -0.120396 0.3048)
			(end -0.120396 0.2794)
			(stroke
				(width 0.1)
				(type default)
			)
			(layer "B.Fab")
		)
		(fp_line
			(start -0.67945 0.3048)
			(end -0.120396 0.3048)
			(stroke
				(width 0.1)
				(type default)
			)
			(layer "B.Fab")
		)
		(pad "1" smd circle
			(at 0.40005 0 270)
			(size 0 0)
			(layers "B.Cu" "B.Mask" "B.Paste")
			(net "P0V9_CPU1_RT_2D")
		)
		(pad "2" smd circle
			(at -0.40005 0 270)
			(size 0 0)
			(layers "B.Cu" "B.Mask" "B.Paste")
			(net "GND")
		)
	)
	(footprint ""
		(layer "B.Cu")
		(at 22.479 -363.347 180)
		(property "Reference" "R240"
			(at 0 0 0)
			(layer "B.SilkS")
			(hide yes)
			(effects
				(font
					(size 1.27 1.27)
				)
				(justify mirror)
			)
		)
		(property "Value" ""
			(at 0 0 0)
			(layer "B.Fab")
			(effects
				(font
					(size 1.27 1.27)
				)
				(justify mirror)
			)
		)
		(duplicate_pad_numbers_are_jumpers no)
		(fp_line
			(start 0.7874 0.4064)
			(end 0.7874 -0.4064)
			(stroke
				(width 0.1524)
				(type default)
			)
			(layer "B.SilkS")
		)
		(fp_line
			(start 0.7874 -0.4064)
			(end -0.7874 -0.4064)
			(stroke
				(width 0.1524)
				(type default)
			)
			(layer "B.SilkS")
		)
		(fp_line
			(start -0.7874 0.4064)
			(end 0.7874 0.4064)
			(stroke
				(width 0.1524)
				(type default)
			)
			(layer "B.SilkS")
		)
		(fp_line
			(start -0.7874 -0.4064)
			(end -0.7874 0.4064)
			(stroke
				(width 0.1524)
				(type default)
			)
			(layer "B.SilkS")
		)
		(fp_line
			(start 0.67945 0.3048)
			(end 0.67945 -0.305054)
			(stroke
				(width 0.1)
				(type default)
			)
			(layer "B.Fab")
		)
		(fp_line
			(start 0.67945 -0.305054)
			(end 0.12065 -0.305054)
			(stroke
				(width 0.1)
				(type default)
			)
			(layer "B.Fab")
		)
		(fp_line
			(start 0.12065 0.3048)
			(end 0.67945 0.3048)
			(stroke
				(width 0.1)
				(type default)
			)
			(layer "B.Fab")
		)
		(fp_line
			(start 0.12065 0.2794)
			(end 0.12065 0.3048)
			(stroke
				(width 0.1)
				(type default)
			)
			(layer "B.Fab")
		)
		(fp_line
			(start 0.12065 -0.2794)
			(end -0.12065 -0.2794)
			(stroke
				(width 0.1)
				(type default)
			)
			(layer "B.Fab")
		)
		(fp_line
			(start 0.12065 -0.305054)
			(end 0.12065 -0.2794)
			(stroke
				(width 0.1)
				(type default)
			)
			(layer "B.Fab")
		)
		(fp_line
			(start -0.120396 0.3048)
			(end -0.120396 0.2794)
			(stroke
				(width 0.1)
				(type default)
			)
			(layer "B.Fab")
		)
		(fp_line
			(start -0.120396 0.2794)
			(end 0.12065 0.2794)
			(stroke
				(width 0.1)
				(type default)
			)
			(layer "B.Fab")
		)
		(fp_line
			(start -0.12065 -0.2794)
			(end -0.12065 -0.3048)
			(stroke
				(width 0.1)
				(type default)
			)
			(layer "B.Fab")
		)
		(fp_line
			(start -0.12065 -0.3048)
			(end -0.67945 -0.3048)
			(stroke
				(width 0.1)
				(type default)
			)
			(layer "B.Fab")
		)
		(fp_line
			(start -0.67945 0.3048)
			(end -0.120396 0.3048)
			(stroke
				(width 0.1)
				(type default)
			)
			(layer "B.Fab")
		)
		(fp_line
			(start -0.67945 -0.3048)
			(end -0.67945 0.3048)
			(stroke
				(width 0.1)
				(type default)
			)
			(layer "B.Fab")
		)
		(pad "1" smd circle
			(at 0.40005 0)
			(size 0 0)
			(layers "B.Cu" "B.Mask" "B.Paste")
			(net "PVDDCR_CPU1_P1_RESET_N")
		)
		(pad "2" smd circle
			(at -0.40005 0)
			(size 0 0)
			(layers "B.Cu" "B.Mask" "B.Paste")
			(net "PVDDCR_CPU1_P1_RESET_N_R")
		)
	)
)
